# BASEBOARD_FAB2 (Tioga Pass) — schematic netlist excerpt (pin names and nets, part order shuffled) for the footprints in the layout excerpt that follows; sources: Cadence DE-HDL packaged netlist, KiCad conversion of Wiwynn_Tioga_Pass_MB.brd

R9P6  RES  10.0K 1% CHIP  pkg 0402  page 200 : A = P3V3_STBY ; B = FM_UV_ADR_TRIGGER_N
C3N28  CAP_A  22.0UF 4V 20% X6S  pkg 0603V  page 132 : A = PVNN_PCH_STBY ; B = GND
R1U43  374R2F-1-GP  1%  pkg SMD-RG  page 152 : \1\ = P3V3 ; \2\ = P0V7_GTL2014_2

(kicad_pcb
	(version 20260206)
	(generator "pcbnew")
	(generator_version "10.0")
	(general
		(thickness 1.6)
		(legacy_teardrops no)
	)
	(paper "A4")
	(title_block
		(title "Wiwynn_Tioga_Pass_MB.brd")
		(comment 1 "Tioga Pass / footprints 3302-3304 of 4770")
	)
	(layers
		(0 "F.Cu" signal "TOP")
		(4 "In1.Cu" signal "L2GND")
		(6 "In2.Cu" signal "L3")
		(8 "In3.Cu" signal "L4GND")
		(10 "In4.Cu" signal "L5")
		(12 "In5.Cu" signal "L6GND")
		(14 "In6.Cu" signal "L7VCC")
		(16 "In7.Cu" signal "L8VCC")
		(18 "In8.Cu" signal "L9GND")
		(20 "In9.Cu" signal "L10")
		(22 "In10.Cu" signal "L11GND")
		(24 "In11.Cu" signal "L12")
		(26 "In12.Cu" signal "L13GND")
		(2 "B.Cu" signal "BOTTOM")
		(9 "F.Adhes" user "F.Adhesive")
		(11 "B.Adhes" user "B.Adhesive")
		(13 "F.Paste" user "Package Geometry/Pastemask Top")
		(15 "B.Paste" user "Package Geometry/Pastemask Bottom")
		(5 "F.SilkS" user "Ref Des/Silkscreen Top")
		(7 "B.SilkS" user "Ref Des/Silkscreen Bottom")
		(1 "F.Mask" user "Board Geometry/Soldermask Top")
		(3 "B.Mask" user "Board Geometry/Soldermask Bottom")
		(17 "Dwgs.User" user "User.Drawings")
		(19 "Cmts.User" user "User.Comments")
		(21 "Eco1.User" user "User.Eco1")
		(23 "Eco2.User" user "User.Eco2")
		(25 "Edge.Cuts" user "Board Geometry/Outline")
		(27 "Margin" user)
		(31 "F.CrtYd" user "Package Geometry/Place Bound Top")
		(29 "B.CrtYd" user "Package Geometry/Place Bound Bottom")
		(35 "F.Fab" user "Ref Des/Assembly Top")
		(33 "B.Fab" user "Ref Des/Assembly Bottom")
	)
	(footprint ""
		(layer "B.Cu")
		(at 442.6712 -15.5702 -90)
		(property "Reference" "R1U43"
			(at 0 0 90)
			(layer "B.SilkS")
			(hide yes)
			(effects
				(font
					(size 1.27 1.27)
				)
				(justify mirror)
			)
		)
		(property "Value" "*"
			(at -0.064008 -4.108196 270)
			(unlocked yes)
			(layer "B.Fab")
			(hide yes)
			(effects
				(font
					(size 1.27 1.016)
					(thickness 0.1524)
				)
				(justify mirror)
			)
		)
		(property "Device Type" "374R2F-1-GP_SMD-RG-374R2F-1-GPA"
			(at -0.064008 -5.632196 270)
			(unlocked yes)
			(layer "B.Fab")
			(hide yes)
			(effects
				(font
					(size 1.27 1.016)
					(thickness 0.1524)
				)
				(justify mirror)
			)
		)
		(duplicate_pad_numbers_are_jumpers no)
		(fp_line
			(start -0.508 -0.9398)
			(end 0.508 -0.9398)
			(stroke
				(width 0.1524)
				(type default)
			)
			(layer "B.SilkS")
		)
		(fp_line
			(start 0.508 -0.9398)
			(end 0.508 0.9398)
			(stroke
				(width 0.1524)
				(type default)
			)
			(layer "B.SilkS")
		)
		(fp_rect
			(start 0.508 0.9398)
			(end -0.508 -0.9398)
			(stroke
				(width 0)
				(type default)
			)
			(fill no)
			(layer "B.CrtYd")
		)
		(fp_rect
			(start 0.508 0.9398)
			(end -0.508 -0.9398)
			(stroke
				(width 0)
				(type default)
			)
			(fill no)
			(layer "B.Fab")
		)
		(pad "1" smd custom
			(at 0 -0.4445 90)
			(size 0.1397 0.1397)
			(layers "B.Cu" "B.Mask" "B.Paste")
			(net "P3V3")
			(options
				(clearance outline)
				(anchor circle)
			)
			(primitives
				(gr_poly
					(pts
						(arc
							(start -0.1778 0.2794)
							(mid -0.249642 0.249642)
							(end -0.2794 0.1778)
						)
						(arc
							(start -0.2794 -0.1778)
							(mid -0.249642 -0.249642)
							(end -0.1778 -0.2794)
						)
						(arc
							(start 0.1778 -0.2794)
							(mid 0.249642 -0.249642)
							(end 0.2794 -0.1778)
						)
						(arc
							(start 0.2794 0.1778)
							(mid 0.249642 0.249642)
							(end 0.1778 0.2794)
						)
					)
					(width 0)
					(fill yes)
				)
			)
		)
		(pad "2" smd custom
			(at 0 0.4445 90)
			(size 0.1397 0.1397)
			(layers "B.Cu" "B.Mask" "B.Paste")
			(net "P0V7_GTL2014_2")
			(options
				(clearance outline)
				(anchor circle)
			)
			(primitives
				(gr_poly
					(pts
						(arc
							(start -0.1778 0.2794)
							(mid -0.249642 0.249642)
							(end -0.2794 0.1778)
						)
						(arc
							(start -0.2794 -0.1778)
							(mid -0.249642 -0.249642)
							(end -0.1778 -0.2794)
						)
						(arc
							(start 0.1778 -0.2794)
							(mid 0.249642 -0.249642)
							(end 0.2794 -0.1778)
						)
						(arc
							(start 0.2794 0.1778)
							(mid 0.249642 0.249642)
							(end 0.1778 0.2794)
						)
					)
					(width 0)
					(fill yes)
				)
			)
		)
	)
	(footprint ""
		(layer "B.Cu")
		(at 24.257 -85.9028 -90)
		(property "Reference" "R9P6"
			(at 0 0 90)
			(layer "B.SilkS")
			(hide yes)
			(effects
				(font
					(size 1.27 1.27)
				)
				(justify mirror)
			)
		)
		(property "Value" ""
			(at 0 0 90)
			(layer "B.Fab")
			(effects
				(font
					(size 1.27 1.27)
				)
				(justify mirror)
			)
		)
		(duplicate_pad_numbers_are_jumpers no)
		(fp_poly
			(pts
				(xy 0.2794 -0.1016) (xy -0.2794 -0.1016) (xy -0.2794 0.9906) (xy 0.2794 0.9906)
			)
			(stroke
				(width 0)
				(type default)
			)
			(fill no)
			(layer "B.CrtYd")
		)
		(fp_line
			(start -0.2794 0.9906)
			(end -0.2794 -0.1016)
			(stroke
				(width 0.1)
				(type default)
			)
			(layer "B.Fab")
		)
		(fp_line
			(start 0.2794 0.9906)
			(end -0.2794 0.9906)
			(stroke
				(width 0.1)
				(type default)
			)
			(layer "B.Fab")
		)
		(fp_line
			(start -0.2794 -0.1016)
			(end 0.2794 -0.1016)
			(stroke
				(width 0.1)
				(type default)
			)
			(layer "B.Fab")
		)
		(fp_line
			(start 0.2794 -0.1016)
			(end 0.2794 0.9906)
			(stroke
				(width 0.1)
				(type default)
			)
			(layer "B.Fab")
		)
		(pad "1" smd rect
			(at 0 0 90)
			(size 0.508 0.508)
			(layers "B.Cu" "B.Mask" "B.Paste")
			(net "P3V3_STBY")
		)
		(pad "2" smd rect
			(at 0 0.889 90)
			(size 0.508 0.508)
			(layers "B.Cu" "B.Mask" "B.Paste")
			(net "FM_UV_ADR_TRIGGER_N")
		)
		(zone
			(layer "B.Cu")
			(hatch none 0.5)
			(connect_pads
				(clearance 0)
			)
			(min_thickness 0.25)
			(keepout
				(tracks not_allowed)
				(vias allowed)
				(pads allowed)
				(copperpour not_allowed)
				(footprints allowed)
			)
			(placement
				(enabled no)
				(sheetname "")
			)
			(fill
				(thermal_gap 0.5)
				(thermal_bridge_width 0.5)
				(island_removal_mode 0)
			)
			(polygon
				(pts
					(xy 23.622 -85.6488) (xy 23.622 -86.1568) (xy 24.003 -86.1568) (xy 24.003 -85.6488)
				)
			)
		)
		(zone
			(layer "B.Cu")
			(hatch none 0.5)
			(connect_pads
				(clearance 0)
			)
			(min_thickness 0.25)
			(keepout
				(tracks allowed)
				(vias not_allowed)
				(pads allowed)
				(copperpour not_allowed)
				(footprints allowed)
			)
			(placement
				(enabled no)
				(sheetname "")
			)
			(fill
				(thermal_gap 0.5)
				(thermal_bridge_width 0.5)
				(island_removal_mode 0)
			)
			(polygon
				(pts
					(xy 24.003 -85.6488) (xy 24.003 -86.1568) (xy 23.622 -86.1568) (xy 23.622 -85.6488)
				)
			)
		)
	)
	(footprint ""
		(layer "B.Cu")
		(at 368.935 -103.632 -90)
		(property "Reference" "C3N28"
			(at 0 0 90)
			(layer "B.SilkS")
			(hide yes)
			(effects
				(font
					(size 1.27 1.27)
				)
				(justify mirror)
			)
		)
		(property "Value" ""
			(at 0 0 90)
			(layer "B.Fab")
			(effects
				(font
					(size 1.27 1.27)
				)
				(justify mirror)
			)
		)
		(duplicate_pad_numbers_are_jumpers no)
		(fp_poly
			(pts
				(xy 0.4953 -0.2032) (xy -0.4953 -0.2032) (xy -0.4953 1.6002) (xy 0.4953 1.6002)
			)
			(stroke
				(width 0)
				(type default)
			)
			(fill no)
			(layer "B.CrtYd")
		)
		(fp_line
			(start -0.4953 1.6002)
			(end 0.4953 1.6002)
			(stroke
				(width 0.1)
				(type default)
			)
			(layer "B.Fab")
		)
		(fp_line
			(start 0.4953 1.6002)
			(end 0.4953 -0.2032)
			(stroke
				(width 0.1)
				(type default)
			)
			(layer "B.Fab")
		)
		(fp_line
			(start -0.4953 -0.2032)
			(end -0.4953 1.6002)
			(stroke
				(width 0.1)
				(type default)
			)
			(layer "B.Fab")
		)
		(fp_line
			(start 0.4953 -0.2032)
			(end -0.4953 -0.2032)
			(stroke
				(width 0.1)
				(type default)
			)
			(layer "B.Fab")
		)
		(pad "1" smd rect
			(at 0 0 90)
			(size 0.762 0.889)
			(layers "B.Cu" "B.Mask" "B.Paste")
			(net "PVNN_PCH_STBY")
		)
		(pad "2" smd rect
			(at 0 1.397 90)
			(size 0.762 0.889)
			(layers "B.Cu" "B.Mask" "B.Paste")
			(net "GND")
		)
		(zone
			(layer "B.Cu")
			(hatch none 0.5)
			(connect_pads
				(clearance 0)
			)
			(min_thickness 0.25)
			(keepout
				(tracks not_allowed)
				(vias allowed)
				(pads allowed)
				(copperpour not_allowed)
				(footprints allowed)
			)
			(placement
				(enabled no)
				(sheetname "")
			)
			(fill
				(thermal_gap 0.5)
				(thermal_bridge_width 0.5)
				(island_removal_mode 0)
			)
			(polygon
				(pts
					(xy 368.4905 -103.251) (xy 368.4905 -104.013) (xy 367.9825 -104.013) (xy 367.9825 -103.251)
				)
			)
		)
	)
)
